# BASEBOARD_FAB2 (Tioga Pass) — schematic parts with pin connectivity, parts 2300–2326 of 4751; source: Cadence DE-HDL packaged netlist (pstxprt.dat, pstxnet.dat, pstchip.dat)

EU7F1  NCP3232L  IC  pkg SM  page 231
  1  SS  BI  = VR_PVPP_ABC_SS
  2  FB  BI  = VR_FB_PVPP_ABC
  3  COMP  OUT  = VR_COMP_PVPP_ABC_3
  4  ISET  BI  = VR_PVPP_ABC_ISET
  5  AGND  GROUND  = AGND_PVPP_ABC
  6  OTS  IN  = AGND_PVPP_ABC
  7  PG  BI  = PWRGD_PVPP_ABC_R
  8  VIN(0)  IN  = VR_FET_SW_P12V_STBY_PVPP_ABC
  9  VIN(1)  IN  = VR_FET_SW_P12V_STBY_PVPP_ABC
  10  VIN(2)  IN  = VR_FET_SW_P12V_STBY_PVPP_ABC
  11  VIN(3)  IN  = VR_FET_SW_P12V_STBY_PVPP_ABC
  12  VIN(4)  IN  = VR_FET_SW_P12V_STBY_PVPP_ABC
  13  VIN(5)  IN  = VR_FET_SW_P12V_STBY_PVPP_ABC
  14  VIN(6)  IN  = VR_FET_SW_P12V_STBY_PVPP_ABC
  15  VSWH(0)  BI  = VR_PVPP_ABC_PHASE
  16  PGND(0)  GROUND  = GND
  17  PGND(1)  GROUND  = GND
  18  PGND(2)  GROUND  = GND
  19  PGND(3)  GROUND  = GND
  20  PGND(4)  GROUND  = GND
  21  PGND(5)  GROUND  = GND
  22  PGND(6)  GROUND  = GND
  23  PGND(7)  GROUND  = GND
  24  PGND(8)  GROUND  = GND
  25  PGND(9)  GROUND  = GND
  26  PGND(10)  GROUND  = GND
  27  PGND(11)  GROUND  = GND
  28  PGND(12)  GROUND  = GND
  29  VSWH(1)  BI  = VR_PVPP_ABC_PHASE
  30  VSWH(2)  BI  = VR_PVPP_ABC_PHASE
  31  VSWH(3)  BI  = VR_PVPP_ABC_PHASE
  32  VSWH(4)  BI  = VR_PVPP_ABC_PHASE
  33  VSWH(5)  BI  = VR_PVPP_ABC_PHASE
  34  VSWH(6)  BI  = VR_PVPP_ABC_PHASE
  35  VSW  BI  = VR_PVPP_ABC_PHASE
  36  BST  IN  = VR_PVPP_ABC_BOOT
  37  PGND(13)  GROUND  = GND
  38  VB  OUT  = VR_VB_PVPP_ABC
  39  VCC  POWER  = VR_FET_SW_P12V_STBY_PVPP_ABC
  40  EN  IN  = FM_PVPP_PVDDQ_CPU0_EN_ABC
  41  GND  GROUND  = GND
  42  VIN(7)  IN  = VR_FET_SW_P12V_STBY_PVPP_ABC
  43  VSWH(7)  BI  = VR_PVPP_ABC_PHASE

EU7G1  PXM1310B  IC  pkg QFN  page 215
  1  BPWM1  OUT  = NC
  2  DNC(0)  NC  = NC
  3  APWM3  OUT  = NC
  4  APWM2  OUT  = VR_PVDDQ_ABC_PWM2
  5  APWM1  OUT  = VR_PVDDQ_ABC_PWM1
  6  SDA  BI  = SMB_VR_STBY_LVC3_SDA
  7  SCL  BI  = SMB_VR_STBY_LVC3_SCL
  8  RESET_N  IN  = NC
  9  AVRRDY  OUT  = PWRGD_PVDDQ_ABC_R
  10  AVREN  IN  = VR_PVDDQ_ABC_VREN
  11  VRHOT_N  OUT  = IRQ_PVDDQ_ABC_VRHOT_LVT3_R_N
  12  PINALRT_N  OUT  = NC
  13  MP0  BI  = PU_VR_PVDDQ_ABC_FAULT1
  14  MP1  BI  = TP_PVDDQ_ABC_MP1
  15  VCLK  IN  = SVID_CLK_PVDDQ_ABC
  16  VDIO  BI  = SVID_VDIO_PVDDQ_ABC
  17  VALRT_N  OUT  = SVID_ALERT_PVDDQ_ABC
  18  MP2  BI  = TP_PVDDQ_ABC_MP2
  19  AVSEN  IN  = VR_PVDDQ_ABC_AVSP
  20  AVREF  IN  = VSENSE_PVDDQ_ABC_N
  21  AIREF1  IN  = VR_PVDDQ_ABC_AIREF1
  22  AISEN1  IN  = ISENSE_PVDDQ_ABC_PH1_IMON
  23  AIREF2  IN  = VR_PVDDQ_ABC_AIREF2
  24  AISEN2  IN  = ISENSE_PVDDQ_ABC_PH2_IMON
  25  AIREF3  IN  = NC
  26  AISEN3  IN  = NC
  27  GND  GROUND  = GND
  28  DNC(1)  NC  = NC
  29  BVSEN  IN  = NC
  30  BVREF  IN  = NC
  31  BIREF1  IN  = NC
  32  BISEN1  IN  = GND
  33  XADDR2  IN  = VR_PVDDQ_ABC_XADDR2
  34  BTSEN  IN  = NC
  35  ATSEN  IN  = A_TSENSE_PVDDQ_ABC
  36  XADDR1  IN  = VR_PVDDQ_ABC_XADDR1
  37  VINSEN  IN  = VR_PVDDQ_ABC_VINSEN
  38  IINSEN  IN  = VR_PVDDQ_ABC_AIINSEN
  39  VDD  POWER  = VR_PVDDQ_ABC_VDD
  40  VD12  BI  = VR_PVDDQ_ABC_VD12
  41  THPAD  GROUND  = GND

EU7G2  IR354XX  IR35411 IC  pkg SM  page 216
  1  VOS  BI  = PVDDQ_ABC
  2  LGND  GROUND  = GND
  3  VCC  POWER  = VR_PVDDQ_ABC_PH1_VCIN
  4  VDRV  BI  = P5V_STBY
  5  PGND(0)  GROUND  = GND
  6  GL(0)  BI  = TP_PVDDQ_ABC_PH1_GL_0
  7  PGND(1)  GROUND  = GND
  10  SW  BI  = VR_PVDDQ_ABC_PH1_SW
  25  VIN(0)  POWER  = VR_FET_SW_P12V_STBY_PVDDQ_ABC
  30  VIN(1)  POWER  = VR_FET_SW_P12V_STBY_PVDDQ_ABC
  31  NC  NC  = NC
  32  PHASE  BI  = VR_PVDDQ_ABC_PH1_PHASE
  33  BOOST  BI  = VR_PVDDQ_ABC_PH1_BOOT_R
  34  PWM  IN  = VR_PVDDQ_ABC_PWM1
  35  EN  BI  = P5V_STBY
  36  TOUT_FLT  BI  = A_TSENSE_PVDDQ_ABC
  37  OCSET  BI  = VR_PVDDQ_ABC_PH1_OCSET
  38  IOUT  OUT  = ISENSE_PVDDQ_ABC_PH1_IMON
  39  REFIN  IN  = VR_PVDDQ_ABC_AIREF1
  40  PGND(2)  GROUND  = GND
  41  GL(1)  BI  = TP_PVDDQ_ABC_PH1_GL_1

EU7G3  IR354XX  IR35411 IC  pkg SM  page 216
  1  VOS  BI  = PVDDQ_ABC
  2  LGND  GROUND  = GND
  3  VCC  POWER  = VR_PVDDQ_ABC_PH2_VCIN
  4  VDRV  BI  = P5V_STBY
  5  PGND(0)  GROUND  = GND
  6  GL(0)  BI  = TP_PVDDQ_ABC_PH2_GL_0
  7  PGND(1)  GROUND  = GND
  10  SW  BI  = VR_PVDDQ_ABC_PH2_SW
  25  VIN(0)  POWER  = VR_FET_SW_P12V_STBY_PVDDQ_ABC
  30  VIN(1)  POWER  = VR_FET_SW_P12V_STBY_PVDDQ_ABC
  31  NC  NC  = NC
  32  PHASE  BI  = VR_PVDDQ_ABC_PH2_PHASE
  33  BOOST  BI  = VR_PVDDQ_ABC_PH2_BOOT_R
  34  PWM  IN  = VR_PVDDQ_ABC_PWM2
  35  EN  BI  = P5V_STBY
  36  TOUT_FLT  BI  = A_TSENSE_PVDDQ_ABC
  37  OCSET  BI  = VR_PVDDQ_ABC_PH2_OCSET
  38  IOUT  OUT  = ISENSE_PVDDQ_ABC_PH2_IMON
  39  REFIN  IN  = VR_PVDDQ_ABC_AIREF2
  40  PGND(2)  GROUND  = GND
  41  GL(1)  BI  = TP_PVDDQ_ABC_PH2_GL_1

EU8A1  PXE1110B  IC  pkg QFN  page 235
  1  DNC(0)  NC  = NC
  2  DNC(1)  NC  = NC
  3  BPWM1  OUT  = VR_P1V05_PCH_STBY_PWM1
  4  DNC(2)  NC  = NC
  5  APWM1  OUT  = VR_PVNN_PCH_PWM1
  6  SDA  BI  = SMB_VR_STBY_LVC3_SDA
  7  SCL  BI  = SMB_VR_STBY_LVC3_SCL
  8  RESET_N  IN  = NC
  9  AVRRDY  OUT  = PWRGD_PVNN_PCH_R
  10  AVREN  IN  = VR_PVNN_PCH_VREN
  11  VRHOT_N  OUT  = IRQ_PVNN_PCH_VRHOT_N
  12  PINALRT_N  OUT  = PU_PVNN_PCH_PINALRT_N
  13  MP0  BI  = VID_PCH_CORE_PVNN_AUX_VID_0
  14  MP1  BI  = VID_PCH_CORE_PVNN_AUX_VID_1
  15  VCLK  IN  = PU_PVNN_PCH_VCLK
  16  VDIO  BI  = PU_PVNN_PCH_VDIO
  17  VALRT_N  OUT  = NC
  18  MP2  OUT  = NC
  19  AVSEN  IN  = VR_PVNN_PCH_AVSP
  20  AVREF  IN  = VSENSE_PVNN_PCH_STBY_AVSN
  21  AIREF1  IN  = VR_PVNN_PCH_AIREF1
  22  AISEN1  IN  = ISENSE_PVNN_PCH_PH1_IMON
  23  GND(1)  GROUND  = GND
  24  DNC(3)  NC  = NC
  25  BIREF1  IN  = VR_P1V05_PCH_BIREF1
  26  BISEN1  IN  = ISENSE_P1V05_PCH_STBY_PH1_IMON
  27  GND(0)  GROUND  = GND
  28  DNC(4)  NC  = NC
  29  BVSEN  IN  = VR_P1V05_PCH_STBY_AVSP
  30  BVREF  IN  = VSENSE_P1V05_PCH_STBY_AVSN
  31  MP3  BI  = NC
  32  MP4  BI  = PU_VR_PVNN_PCH_FAULT1
  33  XADDR2  IN  = VR_PVNN_PCH_XADDR2
  34  BTSEN  IN  = A_TSENSE_P1V05_PCH_STBY_TMON
  35  ATSEN  IN  = A_TSENSE_PVNN_PCH_TMON
  36  XADDR1  IN  = VR_PVNN_PCH_XADDR1
  37  VINSEN  IN  = VR_PVNN_PCH_VINSEN
  38  IINSEN  IN  = NC
  39  VDD  POWER  = VR_PVNN_PCH_VDD
  40  VD12  POWER  = VR_PVNN_P1V05_PCH_VD12
  41  THPAD  GROUND  = GND

EU8A2  RT9059  IC  pkg DFN  page 237
  1  VOUT(0)  OUT  = P1V8_PCH_STBY
  2  VOUT(1)  OUT  = P1V8_PCH_STBY
  3  VOUT(2)  OUT  = P1V8_PCH_STBY
  4  ADJ_NC  OUT  = VR_P1V8_PCH_STBY_FB
  5  PGOOD  OUT  = PWRGD_P1V8_PCH_STBY_R
  6  EN  IN  = PWRGD_P3V3_STBY
  7  VIN(0)  IN  = P3V3_STBY
  8  VIN(1)  IN  = P3V3_STBY
  9  VIN(2)  IN  = P3V3_STBY
  10  VDD  POWER  = P3V3_STBY
  11  GND  GROUND  = GND

EU8B1  SLG55021  IC  pkg SM  page 198
  1  VCC  POWER  = P5V_STBY
  2  \on\  IN  = FM_CTNR_PS_ON
  3  SHDN_N  IN  = P5V_STBY
  4  GND  GROUND  = GND
  5  D  IN  = P5V_STBY
  6  S  IN  = P5V
  7  G  OUT  = P5V_SWITCH_G
  8  PG  OUT  = TP_SLG55021_P5V_8
  9  THPAD  GROUND  = GND

EU8E1  CSD87384M  IC  pkg SM  page 240
  1  TG  IN  = VR_P3V3_STBY_UGATE
  2  VIN  IN  = VR_FET_SW_P12V_STBY_P3V3_STBY
  3  PGND  UNSPEC  = GND
  4  BG  IN  = VR_P3V3_STBY_LGATE
  5  VSW  OUT  = VR_P3V3_STBY_PHASE

EU8F1  RT8240  IC  pkg QFN  page 240
  1  LGATE  OUT  = VR_P3V3_STBY_LGATE
  2  PHASE  IN  = VR_P3V3_STBY_PHASE
  3  UGATE  OUT  = VR_P3V3_STBY_UGATE
  4  BOOT  IN  = VR_P3V3_STBY_BOOT
  5  VCC  POWER  = P5V_STBY
  6  VOUT  OUT  = VSENSE_VOUT_P3V3_STBY
  7  RGND  GROUND  = VSENSE_RGND_P3V3_STBY
  8  EN  IN  = VR_P3V3_STBY_EN
  9  PGOOD  IN  = PWRGD_P3V3_STBY_R
  10  CS  IN  = VR_P3V3_STBY_OCSELECT
  11  G0  IN  = AGND_P3V3_STBY
  12  GND(0)  GROUND  = AGND_P3V3_STBY
  13  GND(1)  GROUND  = AGND_P3V3_STBY

EU8F2  ICS9FGP204  IC  pkg MLFP  page 101
  1  GND(0)  GROUND  = GND
  2  VDD96  POWER  = P3V3_STBY_MNG
  3  DOT96SST  OUT  = TP_CLK_96M_CKMNG_P
  4  DOT96SSC  OUT  = TP_CLK_96M_CKMNG_N
  5  OE_96  IN  = PD_CKMNG_OE
  6  OE_CPU  IN  = PD_CKMNG_OE
  7  CPUCLKT0  OUT  = TP_CLK_100M_R_DP
  8  CPUCLKC0  OUT  = TP_CLK_100M_R_DN
  9  VDDCPU  POWER  = P3V3_STBY_MNG_CPU
  10  GNDCPU  GROUND  = GND
  11  IREF  OUT  = A_COMP_CKMNG
  12  VDD32K  POWER  = P3V3_STBY_MNG
  13  \32khz\  OUT  = CLK_32K_SUSCLK_PLD_R
  14  GND32K  GROUND  = GND
  15  VDDREF  POWER  = P3V3_STBY_MNG
  16  \25mhz_0\  OUT  = CLK_25M_BMC_R
  17  \25mhz_1\  OUT  = CLK_25M_CPLD_R
  18  GNDREF  GROUND  = GND
  19  X1_25  IN  = XTAL_CK_MNG_IN
  20  X2_25  OUT  = XTAL_CK_MNG_OUT_R
  21  GND33  GROUND  = GND
  22  \33mhz_smbadr\  BI  = PU_33P_33M_SMBADR
  23  VDD33  POWER  = P3V3_STBY_MNG
  24  RMII(5)  OUT  = TP_CLK5_50M_CKMNG
  25  RMII(4)  OUT  = CLK_50M_CKMNG_PCH_10GBE_R
  26  VDDRMII(0)  POWER  = P3V3_STBY_MNG_RMII
  27  GNDRMII(0)  GROUND  = GND
  28  RMII(3)  OUT  = CLK_50M_CKMNG_SPRVLLE_R
  29  RMII(2)  OUT  = CLK_50M_CKMNG_BMC_2_R
  30  GNDRMII(1)  GROUND  = GND
  31  VDDRMII(1)  POWER  = P3V3_STBY_MNG_RMII
  32  RMII(1)  OUT  = CLK_50M_CKMNG_BMC_1_R
  33  RMII(0)  OUT  = CLK_50M_CKMNG_OCP_R
  34  VDD_RGMII  IN  = P3V3_STBY_MNG_RGMII
  35  GND_RGMII  GROUND  = GND
  36  RGMII(1)  OUT  = TP_CLK_125M
  37  RGMII(0)  OUT  = TP_CLK_125M_BMCA
  38  SMBCLK  IN  = SMB_HOST_STBY_LVC3_SCL_R4
  39  SMBDAT  BI  = SMB_HOST_STBY_LVC3_SDA_R4
  40  VTTPWR_GD_PD_N  IN  = PWRGD_P3V3_STBY
  41  GND(1)  GROUND  = GND

EU9E1  SPRINGVILLE  IC  pkg SM1  page 139
  1  LAN_PWR_GOOD  IN  = PU_SPRV_LAN_PWR_GOOD
  2  NC_SI_CLK_IN  IN  = CLK_50M_CKMNG_SPRVLLE
  3  NC_SI_CRS_DV  OUT  = RMII_BMC_PCH_SPRNGVLLE_CRSDV_R
  4  JTAG_TDO  OUT  = PU_JTAG_SPRV_TDO
  5  NC_SI_RXD1  OUT  = RMII_SPRNGVLLE_BMC_PCH_RXD1_R
  6  NC_SI_RXD0  OUT  = RMII_SPRNGVLLE_BMC_PCH_RXD0_R
  7  NC_SI_TX_EN  IN  = RMII_BMC_PCH_SPRNGVLLE_TXEN
  8  NC_SI_TXD1  IN  = RMII_BMC_PCH_SPRNGVLLE_TXD1
  9  NC_SI_TXD0  IN  = RMII_BMC_PCH_SPRNGVLLE_TXD0
  10  VDD3P3(4)  POWER  = P3V3_STBY
  11  VDD0P9(2)  POWER  = P0V9_LAN
  12  NVM_SI  OUT  = SPI_NIC_MOSI_R
  13  NVM_SK  OUT  = SPI_NIC_SCLK_R
  14  NVM_SO  IN  = SPI_NIC_MISO
  15  NVM_CS_N  OUT  = SPI_NIC_CS_R_N
  16  PE_WAKE_N  BI  = FM_PE_SPRV_WAKE_N
  17  PE_RST_N  IN  = RST_PLTRST_SPRV_R_N
  18  JTAG_TMS  IN  = PU_JTAG_SPRV_TMS
  19  JTAG_CLK  IN  = PU_JTAG_SPRV_TCK
  20  PE_TN  OUT  = PE_PCH_SPRV_RX_DN
  21  PE_TP  OUT  = PE_PCH_SPRV_RX_DP
  22  NC  IN  = NC
  23  PE_RN  IN  = PE_PCH_SPRV_TX_C_DN
  24  PE_RP  IN  = PE_PCH_SPRV_TX_C_DP
  25  PECLKN  IN  = CLK_100M_SPRV_DN
  26  PECLKP  IN  = CLK_100M_SPRV_DP
  27  VDD3P3(3)  POWER  = P3V3_STBY
  28  DEV_OFF_N  IN  = PU_DEV_OFF_N
  29  JTAG_TDI  IN  = PU_JTAG_SPRV_TDI
  30  LED1  OUT  = LED_LAN_1_N
  31  LED0  OUT  = LED_LAN_0_N
  32  VDD0P9(1)  POWER  = P0V9_LAN
  33  LED2  OUT  = LED_LAN_2_N
  34  SMB_CLK  BI  = SMB_SPRINGVILLE_STBY_LVC3_SCL
  35  SMB_ALRT_N  OUT  = IRQ_LOM_ALERT_N
  36  SMB_DATA  BI  = SMB_SPRINGVILLE_STBY_LVC3_SDA
  37  CBOT  UNSPEC  = A_CBOT
  38  VDD0P9_OUT  POWER  = P0V9_LAN_I210
  39  VDD1P5_OUT  POWER  = P1V5_LAN
  40  CTOP  UNSPEC  = A_CTOP
  41  VDD3P3(2)  POWER  = P3V3_STBY
  42  VDD0P9(3)  POWER  = P0V9_LAN
  43  NC_SI_ARB_IN  IN  = RMII_PCH_SPRNGVLLE_ARB_OUT
  44  NC_SI_ARB_OUT  OUT  = RMII_PCH_SPRNGVLLE_ARB_IN_R
  45  XTAL2  OUT  = XTAL_25MHZ_OUT
  46  XTAL1  IN  = XTAL_25MHZ_IN_R
  47  VDD1P5(1)  POWER  = P1V5_LAN
  48  RSET  UNSPEC  = PD_SPRV_RSET
  49  MDI_MINUS3_SERN  BI  = NIC_SER_N_MDI_3_DN
  50  MDI_PLUS3_SERP  BI  = NIC_SER_P_MDI_3_DP
  51  VDD3P3(1)  POWER  = P3V3_STBY_P1V5_LAN_I210
  52  MDI_MINUS2_SETN  BI  = NIC_SET_N_MDI_2_DN
  53  MDI_PLUS2_SETP  BI  = NIC_SET_P_MDI_2_DP
  54  MDI_MINUS1_SRDS_SIG_DET  BI  = NIC_MDI_SPRV_RJ45_1_DN
  55  MDI_PLUS1_SFP_I2C_CLK  BI  = NIC_MDI_SPRV_RJ45_1_DP
  56  VDD1P5(0)  POWER  = P1V5_LAN_I210
  57  MDI_MINUS0_SFP_I2C_DATA  BI  = NIC_MDI_SPRV_RJ45_0_DN
  58  MDI_PLUS0_NC  BI  = NIC_MDI_SPRV_RJ45_0_DP
  59  VDD0P9(0)  POWER  = P0V9_LAN
  60  SDP3  BI  = TP_SPRV_SDP3
  61  SDP1_PCIE_DIS_SDP1  BI  = FM_1GB_LOM_DISABLE_N
  62  SDP2  BI  = TP_SPRV_SDP2
  63  SDP0  BI  = TP_SPRV_SDP0
  64  VDD3P3(0)  POWER  = P3V3_STBY
  65  GND  GROUND  = GND

EU9F1  RT9059  IC  pkg DFN  page 238
  1  VOUT(0)  OUT  = P1V15_AUX_BMC
  2  VOUT(1)  OUT  = P1V15_AUX_BMC
  3  VOUT(2)  OUT  = P1V15_AUX_BMC
  4  ADJ_NC  OUT  = VR_P1V15_BMC_STBY_FB
  5  PGOOD  OUT  = PWRGD_P1V15_BMC_STBY_R
  6  EN  IN  = PWRGD_P1V2_BMC_STBY
  7  VIN(0)  IN  = P3V3_STBY
  8  VIN(1)  IN  = P3V3_STBY
  9  VIN(2)  IN  = P3V3_STBY
  10  VDD  POWER  = P3V3_STBY
  11  GND  GROUND  = GND

EU9F2  RT9059  IC  pkg DFN  page 239
  1  VOUT(0)  OUT  = P1V2_AUX_BMC
  2  VOUT(1)  OUT  = P1V2_AUX_BMC
  3  VOUT(2)  OUT  = P1V2_AUX_BMC
  4  ADJ_NC  OUT  = VR_P1V2_BMC_STBY_FB
  5  PGOOD  OUT  = PWRGD_P1V2_BMC_STBY_R
  6  EN  IN  = PWRGD_P2V5_BMC_STBY
  7  VIN(0)  IN  = P3V3_STBY
  8  VIN(1)  IN  = P3V3_STBY
  9  VIN(2)  IN  = P3V3_STBY
  10  VDD  POWER  = P3V3_STBY
  11  GND  GROUND  = GND

EU9M1  SLG55021  IC  pkg SM  page 198
  1  VCC  POWER  = P5V_STBY
  2  \on\  IN  = FM_ENABLE_FAN_POWER
  3  SHDN_N  IN  = P5V_STBY
  4  GND  GROUND  = GND
  5  D  IN  = P12V_STBY
  6  S  IN  = P12V_FAN
  7  G  OUT  = P12V_FAN_SWITCH_G
  8  PG  OUT  = TP_SLG55021_P12V_FAN_8
  9  THPAD  GROUND  = GND

EU9R1  MOSFETN_1D3S  IC  pkg SOT5  page 200
  1  S1  UNSPEC  = P12V_STBY
  2  S2  UNSPEC  = P12V_STBY
  3  S3  UNSPEC  = P12V_STBY
  4  G  IN  = A_HSC_GATE2_R
  5  D  UNSPEC  = P12V_MB0_SW

EU25F2  RT9059  IC  pkg DFN  page 239
  1  VOUT(0)  OUT  = P2V5_AUX_BMC
  2  VOUT(1)  OUT  = P2V5_AUX_BMC
  3  VOUT(2)  OUT  = P2V5_AUX_BMC
  4  ADJ_NC  OUT  = VR_P2V5_BMC_STBY_FB
  5  PGOOD  OUT  = PWRGD_P2V5_BMC_STBY_R
  6  EN  IN  = PWRGD_P3V3_STBY
  7  VIN(0)  IN  = P3V3_STBY
  8  VIN(1)  IN  = P3V3_STBY
  9  VIN(2)  IN  = P3V3_STBY
  10  VDD  POWER  = P3V3_STBY
  11  GND  GROUND  = GND

F1L1  FUSE  IC  pkg SMT  page 155 : 1 = P5V_STBY_DBG ; 2 = P5V_STBY_DGB_FS
F8B1  FUSE-3A75V-GP  pkg DISCRET-G5  page 172 : 1 = P5V_HDD_SATA ; 2 = P5V
F9B1  FUSE  IC  pkg SM  page 172 : 1 = P12V ; 2 = P12V_HDD_SATA
F25W1  POLYSW-D5A6V-2-GP-U  pkg DISCRET-GA1  page 252 : 1 = P5V_VGA ; 2 = P5V_VGA_D
F30W1  POLYSW-1D1A6V-2-GP-U  pkg DISCRET-G7  page 253 : 1 = P5V_STBY ; 2 = P5V_STBY_USBC
FB1U3  FERRITE  30 FB  pkg SMLF  page 169 : 1 = A_P1V05_STBY_PCH_SENSOR ; 2 = P1V05_PCH_STBY
FB1U4  FERRITE  30 FB  pkg SMLF  page 169 : 1 = A_PVNN_STBY_PCH_SENSOR ; 2 = PVNN_PCH_STBY
FB2M1  FERRITE  120 FB  pkg SM  page 127 : 1 = P1V05_PCH_STBY ; 2 = P1V05_PCH_STBY_WM20_PLL
FB2M2  FERRITE  120 FB  pkg SM  page 127 : 1 = P1V05_PCH_STBY ; 2 = P1V05_PCH_STBY_WM26_PLL
FB2T1  HCB1608KF-800T30-GP  pkg DISCRET-G9  page 149 : 1 = P3V3_STBY ; 2 = VCC_VA_3V3
FB2T2  FERRITE  600 FB  pkg SMLF  page 101 : 1 = P3V3_STBY ; 2 = P3V3_STBY_MNG
